# S9S_MB_2U (Grand Teton) — schematic netlist excerpt (pin names and nets, part order shuffled) for the footprints in the layout excerpt that follows; sources: Cadence DE-HDL packaged netlist, KiCad conversion of 03242023_DA0F0TMBIJ0_F0T_Motherboard_J_brd_V01_OCP.brd

R3124  Q_RES  0 5% CHIP  pkg 0402LF  page 236 : A = SMB_S3M_CPU0_PIROM_3V3AUX_SDA_R ; B = SMB_S3M_CPU0_PIROM_3V3AUX_SDA
R1214  Q_RES  0 5% CHIP  pkg 0402LF  page 202 : A = IRQ_LPC_PIRQA_N_ESPI_ALERT0_N ; B = IRQ_LPC_PIRQA_N_ESPI_ALERT0_R_N

(kicad_pcb
	(version 20260206)
	(generator "pcbnew")
	(generator_version "10.0")
	(general
		(thickness 1.6)
		(legacy_teardrops no)
	)
	(paper "A4")
	(title_block
		(title "03242023_DA0F0TMBIJ0_F0T_Motherboard_J_brd_V01_OCP.brd")
		(comment 1 "Grand Teton / footprints 106-107 of 6105")
	)
	(layers
		(0 "F.Cu" signal "TOP")
		(4 "In1.Cu" signal "GND")
		(6 "In2.Cu" signal "IN1")
		(8 "In3.Cu" signal "GND1")
		(10 "In4.Cu" signal "IN2")
		(12 "In5.Cu" signal "GND2")
		(14 "In6.Cu" signal "IN3")
		(16 "In7.Cu" signal "GND3")
		(18 "In8.Cu" signal "VCC")
		(20 "In9.Cu" signal "VCC1")
		(22 "In10.Cu" signal "GND4")
		(24 "In11.Cu" signal "IN4")
		(26 "In12.Cu" signal "GND5")
		(28 "In13.Cu" signal "IN5")
		(30 "In14.Cu" signal "GND6")
		(32 "In15.Cu" signal "IN6")
		(34 "In16.Cu" signal "GND7")
		(2 "B.Cu" signal "BOTTOM")
		(9 "F.Adhes" user "F.Adhesive")
		(11 "B.Adhes" user "B.Adhesive")
		(13 "F.Paste" user "Package Geometry/Pastemask Top")
		(15 "B.Paste" user "Package Geometry/Pastemask Bottom")
		(5 "F.SilkS" user "Ref Des/Silkscreen Top")
		(7 "B.SilkS" user "Ref Des/Silkscreen Bottom")
		(1 "F.Mask" user "Board Geometry/Soldermask Top")
		(3 "B.Mask" user "Board Geometry/Soldermask Bottom")
		(17 "Dwgs.User" user "User.Drawings")
		(19 "Cmts.User" user "User.Comments")
		(21 "Eco1.User" user "User.Eco1")
		(23 "Eco2.User" user "User.Eco2")
		(25 "Edge.Cuts" user "Board Geometry/Outline")
		(27 "Margin" user)
		(31 "F.CrtYd" user "Package Geometry/Place Bound Top")
		(29 "B.CrtYd" user "Package Geometry/Place Bound Bottom")
		(35 "F.Fab" user "Ref Des/Assembly Top")
		(33 "B.Fab" user "Ref Des/Assembly Bottom")
	)
	(footprint ""
		(layer "F.Cu")
		(at 153.370788 -81.88198 90)
		(property "Reference" "R3124"
			(at 0 0 90)
			(layer "F.SilkS")
			(hide yes)
			(effects
				(font
					(size 1.27 1.27)
				)
			)
		)
		(property "Value" ""
			(at 0 0 90)
			(layer "F.Fab")
			(effects
				(font
					(size 1.27 1.27)
				)
			)
		)
		(duplicate_pad_numbers_are_jumpers no)
		(fp_line
			(start 0.7874 -0.4064)
			(end 0.7874 0.4064)
			(stroke
				(width 0.1524)
				(type default)
			)
			(layer "F.SilkS")
		)
		(fp_line
			(start -0.7874 -0.4064)
			(end 0.7874 -0.4064)
			(stroke
				(width 0.1524)
				(type default)
			)
			(layer "F.SilkS")
		)
		(fp_line
			(start 0.7874 0.4064)
			(end -0.7874 0.4064)
			(stroke
				(width 0.1524)
				(type default)
			)
			(layer "F.SilkS")
		)
		(fp_line
			(start -0.7874 0.4064)
			(end -0.7874 -0.4064)
			(stroke
				(width 0.1524)
				(type default)
			)
			(layer "F.SilkS")
		)
		(fp_line
			(start -0.12065 -0.305054)
			(end -0.12065 -0.2794)
			(stroke
				(width 0.1)
				(type default)
			)
			(layer "F.Fab")
		)
		(fp_line
			(start -0.67945 -0.305054)
			(end -0.12065 -0.305054)
			(stroke
				(width 0.1)
				(type default)
			)
			(layer "F.Fab")
		)
		(fp_line
			(start 0.67945 -0.3048)
			(end 0.67945 0.3048)
			(stroke
				(width 0.1)
				(type default)
			)
			(layer "F.Fab")
		)
		(fp_line
			(start 0.12065 -0.3048)
			(end 0.67945 -0.3048)
			(stroke
				(width 0.1)
				(type default)
			)
			(layer "F.Fab")
		)
		(fp_line
			(start 0.12065 -0.2794)
			(end 0.12065 -0.3048)
			(stroke
				(width 0.1)
				(type default)
			)
			(layer "F.Fab")
		)
		(fp_line
			(start -0.12065 -0.2794)
			(end 0.12065 -0.2794)
			(stroke
				(width 0.1)
				(type default)
			)
			(layer "F.Fab")
		)
		(fp_line
			(start 0.120396 0.2794)
			(end -0.12065 0.2794)
			(stroke
				(width 0.1)
				(type default)
			)
			(layer "F.Fab")
		)
		(fp_line
			(start -0.12065 0.2794)
			(end -0.12065 0.3048)
			(stroke
				(width 0.1)
				(type default)
			)
			(layer "F.Fab")
		)
		(fp_line
			(start 0.67945 0.3048)
			(end 0.120396 0.3048)
			(stroke
				(width 0.1)
				(type default)
			)
			(layer "F.Fab")
		)
		(fp_line
			(start 0.120396 0.3048)
			(end 0.120396 0.2794)
			(stroke
				(width 0.1)
				(type default)
			)
			(layer "F.Fab")
		)
		(fp_line
			(start -0.12065 0.3048)
			(end -0.67945 0.3048)
			(stroke
				(width 0.1)
				(type default)
			)
			(layer "F.Fab")
		)
		(fp_line
			(start -0.67945 0.3048)
			(end -0.67945 -0.305054)
			(stroke
				(width 0.1)
				(type default)
			)
			(layer "F.Fab")
		)
		(pad "1" smd circle
			(at -0.40005 0 90)
			(size 0 0)
			(layers "F.Cu" "F.Mask" "F.Paste")
			(net "SMB_S3M_CPU0_PIROM_3V3AUX_SDA_R")
		)
		(pad "2" smd circle
			(at 0.40005 0 90)
			(size 0 0)
			(layers "F.Cu" "F.Mask" "F.Paste")
			(net "SMB_S3M_CPU0_PIROM_3V3AUX_SDA")
		)
	)
	(footprint ""
		(layer "F.Cu")
		(at 336.32648 -22.836632 -90)
		(property "Reference" "R1214"
			(at 0 0 270)
			(layer "F.SilkS")
			(hide yes)
			(effects
				(font
					(size 1.27 1.27)
				)
			)
		)
		(property "Value" ""
			(at 0 0 270)
			(layer "F.Fab")
			(effects
				(font
					(size 1.27 1.27)
				)
			)
		)
		(duplicate_pad_numbers_are_jumpers no)
		(fp_line
			(start -0.7874 0.4064)
			(end -0.7874 -0.4064)
			(stroke
				(width 0.1524)
				(type default)
			)
			(layer "F.SilkS")
		)
		(fp_line
			(start 0.7874 0.4064)
			(end -0.7874 0.4064)
			(stroke
				(width 0.1524)
				(type default)
			)
			(layer "F.SilkS")
		)
		(fp_line
			(start -0.7874 -0.4064)
			(end 0.7874 -0.4064)
			(stroke
				(width 0.1524)
				(type default)
			)
			(layer "F.SilkS")
		)
		(fp_line
			(start 0.7874 -0.4064)
			(end 0.7874 0.4064)
			(stroke
				(width 0.1524)
				(type default)
			)
			(layer "F.SilkS")
		)
		(fp_line
			(start -0.67945 0.3048)
			(end -0.67945 -0.305054)
			(stroke
				(width 0.1)
				(type default)
			)
			(layer "F.Fab")
		)
		(fp_line
			(start -0.12065 0.3048)
			(end -0.67945 0.3048)
			(stroke
				(width 0.1)
				(type default)
			)
			(layer "F.Fab")
		)
		(fp_line
			(start 0.120396 0.3048)
			(end 0.120396 0.2794)
			(stroke
				(width 0.1)
				(type default)
			)
			(layer "F.Fab")
		)
		(fp_line
			(start 0.67945 0.3048)
			(end 0.120396 0.3048)
			(stroke
				(width 0.1)
				(type default)
			)
			(layer "F.Fab")
		)
		(fp_line
			(start -0.12065 0.2794)
			(end -0.12065 0.3048)
			(stroke
				(width 0.1)
				(type default)
			)
			(layer "F.Fab")
		)
		(fp_line
			(start 0.120396 0.2794)
			(end -0.12065 0.2794)
			(stroke
				(width 0.1)
				(type default)
			)
			(layer "F.Fab")
		)
		(fp_line
			(start -0.12065 -0.2794)
			(end 0.12065 -0.2794)
			(stroke
				(width 0.1)
				(type default)
			)
			(layer "F.Fab")
		)
		(fp_line
			(start 0.12065 -0.2794)
			(end 0.12065 -0.3048)
			(stroke
				(width 0.1)
				(type default)
			)
			(layer "F.Fab")
		)
		(fp_line
			(start 0.12065 -0.3048)
			(end 0.67945 -0.3048)
			(stroke
				(width 0.1)
				(type default)
			)
			(layer "F.Fab")
		)
		(fp_line
			(start 0.67945 -0.3048)
			(end 0.67945 0.3048)
			(stroke
				(width 0.1)
				(type default)
			)
			(layer "F.Fab")
		)
		(fp_line
			(start -0.67945 -0.305054)
			(end -0.12065 -0.305054)
			(stroke
				(width 0.1)
				(type default)
			)
			(layer "F.Fab")
		)
		(fp_line
			(start -0.12065 -0.305054)
			(end -0.12065 -0.2794)
			(stroke
				(width 0.1)
				(type default)
			)
			(layer "F.Fab")
		)
		(pad "1" smd circle
			(at -0.40005 0 270)
			(size 0 0)
			(layers "F.Cu" "F.Mask" "F.Paste")
			(net "IRQ_LPC_PIRQA_N_ESPI_ALERT0_N")
		)
		(pad "2" smd circle
			(at 0.40005 0 270)
			(size 0 0)
			(layers "F.Cu" "F.Mask" "F.Paste")
			(net "IRQ_LPC_PIRQA_N_ESPI_ALERT0_R_N")
		)
	)
)
